(kicad_pcb
	(version 20260206)
	(generator "pcbnew")
	(generator_version "10.0")
	(general
		(thickness 1.6)
		(legacy_teardrops no)
	)
	(paper "A4")
	(title_block
		(title "peb — Lightning_PEB_BRD.brd")
		(comment 1 "Lightning (Wiwynn / Facebook NVMe JBOF) / footprints 868-870 of 2563")
	)
	(layers
		(0 "F.Cu" signal "TOP")
		(4 "In1.Cu" signal "L2GND")
		(6 "In2.Cu" signal "L3")
		(8 "In3.Cu" signal "L4VCC")
		(10 "In4.Cu" signal "L5VCC")
		(12 "In5.Cu" signal "L6")
		(14 "In6.Cu" signal "L7GND")
		(2 "B.Cu" signal "BOTTOM")
		(9 "F.Adhes" user "F.Adhesive")
		(11 "B.Adhes" user "B.Adhesive")
		(13 "F.Paste" user "Package Geometry/Pastemask Top")
		(15 "B.Paste" user "Package Geometry/Pastemask Bottom")
		(5 "F.SilkS" user "Ref Des/Silkscreen Top")
		(7 "B.SilkS" user "Ref Des/Silkscreen Bottom")
		(1 "F.Mask" user "Board Geometry/Soldermask Top")
		(3 "B.Mask" user "Board Geometry/Soldermask Bottom")
		(17 "Dwgs.User" user "User.Drawings")
		(19 "Cmts.User" user "User.Comments")
		(21 "Eco1.User" user "User.Eco1")
		(23 "Eco2.User" user "User.Eco2")
		(25 "Edge.Cuts" user "Board Geometry/Outline")
		(27 "Margin" user)
		(31 "F.CrtYd" user "Package Geometry/Place Bound Top")
		(29 "B.CrtYd" user "Package Geometry/Place Bound Bottom")
		(35 "F.Fab" user "Ref Des/Assembly Top")
		(33 "B.Fab" user "Ref Des/Assembly Bottom")
	)
	(footprint ""
		(layer "F.Cu")
		(at 186.0804 -61.595)
		(property "Reference" "C572"
			(at 0 0 0)
			(layer "F.SilkS")
			(hide yes)
			(effects
				(font
					(size 1.27 1.27)
				)
			)
		)
		(property "Value" "SC4D7U16V5KX-1-GP"
			(at -0.0762 -6.1214 0)
			(unlocked yes)
			(layer "F.Fab")
			(hide yes)
			(effects
				(font
					(size 1.016 1.016)
					(thickness 0.1524)
				)
			)
		)
		(property "Device Type" "C805H56"
			(at -0.0762 -8.1534 0)
			(unlocked yes)
			(layer "F.Fab")
			(hide yes)
			(effects
				(font
					(size 1.016 1.016)
					(thickness 0.1524)
				)
			)
		)
		(duplicate_pad_numbers_are_jumpers no)
		(fp_line
			(start 0.635 0)
			(end -0.635 0)
			(stroke
				(width 0.508)
				(type default)
			)
			(layer "F.SilkS")
		)
		(fp_rect
			(start -0.9652 1.778)
			(end 0.9652 -1.778)
			(stroke
				(width 0)
				(type default)
			)
			(fill no)
			(layer "F.CrtYd")
		)
		(fp_poly
			(pts
				(xy -0.9652 -1.778) (xy 0.9652 -1.778) (xy 0.9652 1.778) (xy -0.9652 1.778)
			)
			(stroke
				(width 0)
				(type default)
			)
			(fill no)
			(layer "F.Fab")
		)
		(pad "1" smd rect
			(at 0 -0.9652)
			(size 1.397 1.143)
			(layers "F.Cu" "F.Mask" "F.Paste")
			(net "DUT_AVD_PCIE")
		)
		(pad "2" smd rect
			(at 0 0.9652)
			(size 1.397 1.143)
			(layers "F.Cu" "F.Mask" "F.Paste")
			(net "GND")
		)
	)
	(footprint ""
		(layer "F.Cu")
		(at 230.251 -12.319 90)
		(property "Reference" "C727"
			(at 0 0 90)
			(layer "F.SilkS")
			(hide yes)
			(effects
				(font
					(size 1.27 1.27)
				)
			)
		)
		(property "Value" "SCD1U10V2KX-5GP"
			(at 1.1811 -2.7051 90)
			(unlocked yes)
			(layer "F.Fab")
			(hide yes)
			(effects
				(font
					(size 1.016 1.016)
					(thickness 0.1524)
				)
			)
		)
		(property "Device Type" "C402H22"
			(at 1.1811 -4.2291 90)
			(unlocked yes)
			(layer "F.Fab")
			(hide yes)
			(effects
				(font
					(size 1.016 1.016)
					(thickness 0.1524)
				)
			)
		)
		(duplicate_pad_numbers_are_jumpers no)
		(fp_rect
			(start -0.4318 0.9525)
			(end 0.4318 -0.9525)
			(stroke
				(width 0)
				(type default)
			)
			(fill no)
			(layer "F.CrtYd")
		)
		(fp_rect
			(start -0.4318 0.9525)
			(end 0.4318 -0.9525)
			(stroke
				(width 0)
				(type default)
			)
			(fill no)
			(layer "F.Fab")
		)
		(pad "1" smd custom
			(at 0 -0.4445 90)
			(size 0.1524 0.1524)
			(layers "F.Cu" "F.Mask" "F.Paste")
			(net "P3V3_STBY")
			(options
				(clearance outline)
				(anchor circle)
			)
			(primitives
				(gr_poly
					(pts
						(arc
							(start 0.3048 -0.2032)
							(mid 0.275042 -0.275042)
							(end 0.2032 -0.3048)
						)
						(arc
							(start -0.2032 -0.3048)
							(mid -0.275042 -0.275042)
							(end -0.3048 -0.2032)
						)
						(arc
							(start -0.3048 0.2032)
							(mid -0.275042 0.275042)
							(end -0.2032 0.3048)
						)
						(arc
							(start 0.2032 0.3048)
							(mid 0.275042 0.275042)
							(end 0.3048 0.2032)
						)
					)
					(width 0)
					(fill yes)
				)
			)
		)
		(pad "2" smd custom
			(at 0 0.4445 90)
			(size 0.1524 0.1524)
			(layers "F.Cu" "F.Mask" "F.Paste")
			(net "GND")
			(options
				(clearance outline)
				(anchor circle)
			)
			(primitives
				(gr_poly
					(pts
						(arc
							(start 0.3048 -0.2032)
							(mid 0.275042 -0.275042)
							(end 0.2032 -0.3048)
						)
						(arc
							(start -0.2032 -0.3048)
							(mid -0.275042 -0.275042)
							(end -0.3048 -0.2032)
						)
						(arc
							(start -0.3048 0.2032)
							(mid -0.275042 0.275042)
							(end -0.2032 0.3048)
						)
						(arc
							(start 0.2032 0.3048)
							(mid 0.275042 0.275042)
							(end 0.3048 0.2032)
						)
					)
					(width 0)
					(fill yes)
				)
			)
		)
	)
	(footprint ""
		(layer "F.Cu")
		(at 18.161 -75.6666 -90)
		(property "Reference" "U20"
			(at 0 0 270)
			(layer "F.SilkS")
			(hide yes)
			(effects
				(font
					(size 1.27 1.27)
				)
			)
		)
		(property "Value" "WGI210AT-2-GP"
			(at -7.0358 -7.3787 270)
			(unlocked yes)
			(layer "F.Fab")
			(hide yes)
			(effects
				(font
					(size 1.016 1.016)
					(thickness 0.1524)
				)
			)
		)
		(property "Device Type" "QFN64G9-G3D6H40"
			(at -7.0358 -8.9027 270)
			(unlocked yes)
			(layer "F.Fab")
			(hide yes)
			(effects
				(font
					(size 1.016 1.016)
					(thickness 0.1524)
				)
			)
		)
		(duplicate_pad_numbers_are_jumpers no)
		(fp_line
			(start -5.5118 5.5118)
			(end -4.2418 5.5118)
			(stroke
				(width 0.1524)
				(type default)
			)
			(layer "F.SilkS")
		)
		(fp_line
			(start 4.2418 5.5118)
			(end 5.5118 5.5118)
			(stroke
				(width 0.1524)
				(type default)
			)
			(layer "F.SilkS")
		)
		(fp_line
			(start 5.5118 5.5118)
			(end 5.5118 4.2418)
			(stroke
				(width 0.1524)
				(type default)
			)
			(layer "F.SilkS")
		)
		(fp_line
			(start -2.750058 5.262118)
			(end -2.750058 5.770118)
			(stroke
				(width 0.1524)
				(type default)
			)
			(layer "F.SilkS")
		)
		(fp_line
			(start -0.249936 5.262118)
			(end -0.249936 6.024118)
			(stroke
				(width 0.1524)
				(type default)
			)
			(layer "F.SilkS")
		)
		(fp_line
			(start 2.249932 5.262118)
			(end 2.249932 5.770118)
			(stroke
				(width 0.1524)
				(type default)
			)
			(layer "F.SilkS")
		)
		(fp_line
			(start -5.5118 4.2418)
			(end -5.5118 5.5118)
			(stroke
				(width 0.1524)
				(type default)
			)
			(layer "F.SilkS")
		)
		(fp_line
			(start 5.262118 3.24993)
			(end 6.024118 3.24993)
			(stroke
				(width 0.1524)
				(type default)
			)
			(layer "F.SilkS")
		)
		(fp_line
			(start -5.262118 2.750058)
			(end -6.024118 2.750058)
			(stroke
				(width 0.1524)
				(type default)
			)
			(layer "F.SilkS")
		)
		(fp_line
			(start 5.262118 0.750062)
			(end 5.770118 0.750062)
			(stroke
				(width 0.1524)
				(type default)
			)
			(layer "F.SilkS")
		)
		(fp_line
			(start -5.262118 0.249936)
			(end -5.770118 0.249936)
			(stroke
				(width 0.1524)
				(type default)
			)
			(layer "F.SilkS")
		)
		(fp_line
			(start 5.262118 -1.75006)
			(end 6.024118 -1.75006)
			(stroke
				(width 0.1524)
				(type default)
			)
			(layer "F.SilkS")
		)
		(fp_line
			(start -5.262118 -2.249932)
			(end -6.024118 -2.249932)
			(stroke
				(width 0.1524)
				(type default)
			)
			(layer "F.SilkS")
		)
		(fp_line
			(start -3.24993 -5.262118)
			(end -3.24993 -5.770118)
			(stroke
				(width 0.1524)
				(type default)
			)
			(layer "F.SilkS")
		)
		(fp_line
			(start -0.750062 -5.262118)
			(end -0.750062 -6.024118)
			(stroke
				(width 0.1524)
				(type default)
			)
			(layer "F.SilkS")
		)
		(fp_line
			(start 1.75006 -5.262118)
			(end 1.75006 -5.770118)
			(stroke
				(width 0.1524)
				(type default)
			)
			(layer "F.SilkS")
		)
		(fp_line
			(start -5.5118 -5.5118)
			(end -5.5118 -4.2418)
			(stroke
				(width 0.1524)
				(type default)
			)
			(layer "F.SilkS")
		)
		(fp_line
			(start -4.2418 -5.5118)
			(end -5.5118 -5.5118)
			(stroke
				(width 0.1524)
				(type default)
			)
			(layer "F.SilkS")
		)
		(fp_poly
			(pts
				(xy 5.5118 -5.5118) (xy 4.2418 -5.5118) (xy 5.5118 -4.2418)
			)
			(stroke
				(width 0)
				(type default)
			)
			(fill yes)
			(layer "F.SilkS")
		)
		(fp_rect
			(start -4.4958 4.4958)
			(end 4.4958 -4.4958)
			(stroke
				(width 0)
				(type default)
			)
			(fill no)
			(layer "F.CrtYd")
		)
		(fp_poly
			(pts
				(xy 5.5118 -4.4958) (xy -4.4958 -4.4958) (xy -4.4958 4.4958) (xy 4.4958 4.4958) (xy 4.4958 -4.4831)
				(xy 5.5118 -4.4831) (xy 5.5118 5.5118) (xy -5.5118 5.5118) (xy -5.5118 -5.5118) (xy 5.5118 -5.5118)
			)
			(stroke
				(width 0)
				(type default)
			)
			(fill no)
			(layer "F.CrtYd")
		)
		(fp_rect
			(start -5.5118 5.5118)
			(end 5.5118 -5.5118)
			(stroke
				(width 0)
				(type default)
			)
			(fill no)
			(layer "F.Fab")
		)
		(pad "1" smd rect
			(at 3.750056 -4.423918 270)
			(size 0.3048 0.9144)
			(drill
				(offset 0 -0.127)
			)
			(layers "F.Cu" "F.Mask" "F.Paste")
			(net "LAN_MAIN_PWR_OK")
		)
		(pad "2" smd rect
			(at 3.24993 -4.423918 270)
			(size 0.3048 1.1684)
			(layers "F.Cu" "F.Mask" "F.Paste")
			(net "CLK_50M_RMII_PHY_IN")
		)
		(pad "3" smd rect
			(at 2.750058 -4.423918 270)
			(size 0.3048 1.1684)
			(layers "F.Cu" "F.Mask" "F.Paste")
			(net "RMII_BMC_CRS_DV")
		)
		(pad "4" smd rect
			(at 2.249932 -4.423918 270)
			(size 0.3048 1.1684)
			(layers "F.Cu" "F.Mask" "F.Paste")
			(net "NIC_JTDO")
		)
		(pad "5" smd rect
			(at 1.75006 -4.423918 270)
			(size 0.3048 1.1684)
			(layers "F.Cu" "F.Mask" "F.Paste")
			(net "RMII_PHY_BMC_RXD1_R")
		)
		(pad "6" smd rect
			(at 1.249934 -4.423918 270)
			(size 0.3048 1.1684)
			(layers "F.Cu" "F.Mask" "F.Paste")
			(net "RMII_PHY_BMC_RXD0_R")
		)
		(pad "7" smd rect
			(at 0.750062 -4.423918 270)
			(size 0.3048 1.1684)
			(layers "F.Cu" "F.Mask" "F.Paste")
			(net "RMII_BMC_TX_EN")
		)
		(pad "8" smd rect
			(at 0.249936 -4.423918 270)
			(size 0.3048 1.1684)
			(layers "F.Cu" "F.Mask" "F.Paste")
			(net "RMII_BMC_PHY_TXD1")
		)
		(pad "9" smd rect
			(at -0.249936 -4.423918 270)
			(size 0.3048 1.1684)
			(layers "F.Cu" "F.Mask" "F.Paste")
			(net "RMII_BMC_PHY_TXD0")
		)
		(pad "10" smd rect
			(at -0.750062 -4.423918 270)
			(size 0.3048 1.1684)
			(layers "F.Cu" "F.Mask" "F.Paste")
			(net "P3V3_STBY")
		)
		(pad "11" smd rect
			(at -1.249934 -4.423918 270)
			(size 0.3048 1.1684)
			(layers "F.Cu" "F.Mask" "F.Paste")
			(net "P0V9_I210")
		)
		(pad "12" smd rect
			(at -1.75006 -4.423918 270)
			(size 0.3048 1.1684)
			(layers "F.Cu" "F.Mask" "F.Paste")
			(net "NVM_SI")
		)
		(pad "13" smd rect
			(at -2.249932 -4.423918 270)
			(size 0.3048 1.1684)
			(layers "F.Cu" "F.Mask" "F.Paste")
			(net "NVM_SK")
		)
		(pad "14" smd rect
			(at -2.750058 -4.423918 270)
			(size 0.3048 1.1684)
			(layers "F.Cu" "F.Mask" "F.Paste")
			(net "NVM_SO")
		)
		(pad "15" smd rect
			(at -3.24993 -4.423918 270)
			(size 0.3048 1.1684)
			(layers "F.Cu" "F.Mask" "F.Paste")
			(net "NVM_CS_N")
		)
		(pad "16" smd rect
			(at -3.750056 -4.423918 270)
			(size 0.3048 0.9144)
			(drill
				(offset 0 -0.127)
			)
			(layers "F.Cu" "F.Mask" "F.Paste")
			(net "PHY_WAKE_N")
		)
		(pad "17" smd rect
			(at -4.423918 -3.750056 270)
			(size 0.9144 0.3048)
			(drill
				(offset -0.127 0)
			)
			(layers "F.Cu" "F.Mask" "F.Paste")
			(net "PHY_RESET_N")
		)
		(pad "18" smd rect
			(at -4.423918 -3.24993 270)
			(size 1.1684 0.3048)
			(layers "F.Cu" "F.Mask" "F.Paste")
			(net "NIC_JTMS")
		)
		(pad "19" smd rect
			(at -4.423918 -2.750058 270)
			(size 1.1684 0.3048)
			(layers "F.Cu" "F.Mask" "F.Paste")
			(net "NIC_JTCK")
		)
		(pad "20" smd rect
			(at -4.423918 -2.249932 270)
			(size 1.1684 0.3048)
			(layers "F.Cu" "F.Mask" "F.Paste")
			(net "PCIE_RX_CAP_N78")
		)
		(pad "21" smd rect
			(at -4.423918 -1.75006 270)
			(size 1.1684 0.3048)
			(layers "F.Cu" "F.Mask" "F.Paste")
			(net "PCIE_RX_CAP_P78")
		)
		(pad "22" smd rect
			(at -4.423918 -1.249934 270)
			(size 1.1684 0.3048)
			(layers "F.Cu" "F.Mask" "F.Paste")
			(net "Net_209")
		)
		(pad "23" smd rect
			(at -4.423918 -0.750062 270)
			(size 1.1684 0.3048)
			(layers "F.Cu" "F.Mask" "F.Paste")
			(net "PCIE_TX_N78")
		)
		(pad "24" smd rect
			(at -4.423918 -0.249936 270)
			(size 1.1684 0.3048)
			(layers "F.Cu" "F.Mask" "F.Paste")
			(net "PCIE_TX_P78")
		)
		(pad "25" smd rect
			(at -4.423918 0.249936 270)
			(size 1.1684 0.3048)
			(layers "F.Cu" "F.Mask" "F.Paste")
			(net "I210_REFCLK_D_N")
		)
		(pad "26" smd rect
			(at -4.423918 0.750062 270)
			(size 1.1684 0.3048)
			(layers "F.Cu" "F.Mask" "F.Paste")
			(net "I210_REFCLK_D_P")
		)
		(pad "27" smd rect
			(at -4.423918 1.249934 270)
			(size 1.1684 0.3048)
			(layers "F.Cu" "F.Mask" "F.Paste")
			(net "P3V3_STBY")
		)
		(pad "28" smd rect
			(at -4.423918 1.75006 270)
			(size 1.1684 0.3048)
			(layers "F.Cu" "F.Mask" "F.Paste")
			(net "FM_PCH_LAN1_DISABLE_N")
		)
		(pad "29" smd rect
			(at -4.423918 2.249932 270)
			(size 1.1684 0.3048)
			(layers "F.Cu" "F.Mask" "F.Paste")
			(net "NIC_JTDI")
		)
		(pad "30" smd rect
			(at -4.423918 2.750058 270)
			(size 1.1684 0.3048)
			(layers "F.Cu" "F.Mask" "F.Paste")
			(net "LED_MDI0_LINK_N")
		)
		(pad "31" smd rect
			(at -4.423918 3.24993 270)
			(size 1.1684 0.3048)
			(layers "F.Cu" "F.Mask" "F.Paste")
			(net "LED_MDI0_100M_N")
		)
		(pad "32" smd rect
			(at -4.423918 3.750056 270)
			(size 0.9144 0.3048)
			(drill
				(offset -0.127 0)
			)
			(layers "F.Cu" "F.Mask" "F.Paste")
			(net "P0V9_I210")
		)
		(pad "33" smd rect
			(at -3.750056 4.423918 270)
			(size 0.3048 0.9144)
			(drill
				(offset 0 0.127)
			)
			(layers "F.Cu" "F.Mask" "F.Paste")
			(net "LED_MDI0_1G_N")
		)
		(pad "34" smd rect
			(at -3.24993 4.423918 270)
			(size 0.3048 1.1684)
			(layers "F.Cu" "F.Mask" "F.Paste")
			(net "LAN_SMB_CLK")
		)
		(pad "35" smd rect
			(at -2.750058 4.423918 270)
			(size 0.3048 1.1684)
			(layers "F.Cu" "F.Mask" "F.Paste")
			(net "LAN_SMB_ALERT_N")
		)
		(pad "36" smd rect
			(at -2.249932 4.423918 270)
			(size 0.3048 1.1684)
			(layers "F.Cu" "F.Mask" "F.Paste")
			(net "LAN_SMB_DAT")
		)
		(pad "37" smd rect
			(at -1.75006 4.423918 270)
			(size 0.3048 1.1684)
			(layers "F.Cu" "F.Mask" "F.Paste")
			(net "I210_CBOT")
		)
		(pad "38" smd rect
			(at -1.249934 4.423918 270)
			(size 0.3048 1.1684)
			(layers "F.Cu" "F.Mask" "F.Paste")
			(net "P0V9_I210")
		)
		(pad "39" smd rect
			(at -0.750062 4.423918 270)
			(size 0.3048 1.1684)
			(layers "F.Cu" "F.Mask" "F.Paste")
			(net "P1V5_I210")
		)
		(pad "40" smd rect
			(at -0.249936 4.423918 270)
			(size 0.3048 1.1684)
			(layers "F.Cu" "F.Mask" "F.Paste")
			(net "I210_CTOP")
		)
		(pad "41" smd rect
			(at 0.249936 4.423918 270)
			(size 0.3048 1.1684)
			(layers "F.Cu" "F.Mask" "F.Paste")
			(net "P3V3_STBY")
		)
		(pad "42" smd rect
			(at 0.750062 4.423918 270)
			(size 0.3048 1.1684)
			(layers "F.Cu" "F.Mask" "F.Paste")
			(net "P0V9_I210")
		)
		(pad "43" smd rect
			(at 1.249934 4.423918 270)
			(size 0.3048 1.1684)
			(layers "F.Cu" "F.Mask" "F.Paste")
			(net "NCSI_ARB_IN")
		)
		(pad "44" smd rect
			(at 1.75006 4.423918 270)
			(size 0.3048 1.1684)
			(layers "F.Cu" "F.Mask" "F.Paste")
			(net "NCSI_ARB_OUT")
		)
		(pad "45" smd rect
			(at 2.249932 4.423918 270)
			(size 0.3048 1.1684)
			(layers "F.Cu" "F.Mask" "F.Paste")
			(net "XTAL_OUT_I210")
		)
		(pad "46" smd rect
			(at 2.750058 4.423918 270)
			(size 0.3048 1.1684)
			(layers "F.Cu" "F.Mask" "F.Paste")
			(net "XTAL_IN_I210")
		)
		(pad "47" smd rect
			(at 3.24993 4.423918 270)
			(size 0.3048 1.1684)
			(layers "F.Cu" "F.Mask" "F.Paste")
			(net "P1V5_I210")
		)
		(pad "48" smd rect
			(at 3.750056 4.423918 270)
			(size 0.3048 0.9144)
			(drill
				(offset 0 0.127)
			)
			(layers "F.Cu" "F.Mask" "F.Paste")
			(net "LAN_SE_RSET")
		)
		(pad "49" smd rect
			(at 4.423918 3.750056 270)
			(size 0.9144 0.3048)
			(drill
				(offset 0.127 0)
			)
			(layers "F.Cu" "F.Mask" "F.Paste")
			(net "NIC0_MDI0_N3")
		)
		(pad "50" smd rect
			(at 4.423918 3.24993 270)
			(size 1.1684 0.3048)
			(layers "F.Cu" "F.Mask" "F.Paste")
			(net "NIC0_MDI0_P3")
		)
		(pad "51" smd rect
			(at 4.423918 2.750058 270)
			(size 1.1684 0.3048)
			(layers "F.Cu" "F.Mask" "F.Paste")
			(net "LAN1_51")
		)
		(pad "52" smd rect
			(at 4.423918 2.249932 270)
			(size 1.1684 0.3048)
			(layers "F.Cu" "F.Mask" "F.Paste")
			(net "NIC0_MDI0_N2")
		)
		(pad "53" smd rect
			(at 4.423918 1.75006 270)
			(size 1.1684 0.3048)
			(layers "F.Cu" "F.Mask" "F.Paste")
			(net "NIC0_MDI0_P2")
		)
		(pad "54" smd rect
			(at 4.423918 1.249934 270)
			(size 1.1684 0.3048)
			(layers "F.Cu" "F.Mask" "F.Paste")
			(net "NIC0_MDI0_N1")
		)
		(pad "55" smd rect
			(at 4.423918 0.750062 270)
			(size 1.1684 0.3048)
			(layers "F.Cu" "F.Mask" "F.Paste")
			(net "NIC0_MDI0_P1")
		)
		(pad "56" smd rect
			(at 4.423918 0.249936 270)
			(size 1.1684 0.3048)
			(layers "F.Cu" "F.Mask" "F.Paste")
			(net "LAN1_56")
		)
		(pad "57" smd rect
			(at 4.423918 -0.249936 270)
			(size 1.1684 0.3048)
			(layers "F.Cu" "F.Mask" "F.Paste")
			(net "NIC0_MDI0_N0")
		)
		(pad "58" smd rect
			(at 4.423918 -0.750062 270)
			(size 1.1684 0.3048)
			(layers "F.Cu" "F.Mask" "F.Paste")
			(net "NIC0_MDI0_P0")
		)
		(pad "59" smd rect
			(at 4.423918 -1.249934 270)
			(size 1.1684 0.3048)
			(layers "F.Cu" "F.Mask" "F.Paste")
			(net "P0V9_I210")
		)
		(pad "60" smd rect
			(at 4.423918 -1.75006 270)
			(size 1.1684 0.3048)
			(layers "F.Cu" "F.Mask" "F.Paste")
			(net "TP_SDP3")
		)
		(pad "61" smd rect
			(at 4.423918 -2.249932 270)
			(size 1.1684 0.3048)
			(layers "F.Cu" "F.Mask" "F.Paste")
			(net "PCIE_DIS")
		)
		(pad "62" smd rect
			(at 4.423918 -2.750058 270)
			(size 1.1684 0.3048)
			(layers "F.Cu" "F.Mask" "F.Paste")
			(net "TP_SDP2")
		)
		(pad "63" smd rect
			(at 4.423918 -3.24993 270)
			(size 1.1684 0.3048)
			(layers "F.Cu" "F.Mask" "F.Paste")
			(net "TP_SDP0")
		)
		(pad "64" smd rect
			(at 4.423918 -3.750056 270)
			(size 0.9144 0.3048)
			(drill
				(offset 0.127 0)
			)
			(layers "F.Cu" "F.Mask" "F.Paste")
			(net "P3V3_STBY")
		)
		(pad "65" smd rect
			(at 0 0 270)
			(size 3.6068 3.6068)
			(layers "F.Cu" "F.Mask" "F.Paste")
			(net "GND")
		)
	)
)
